(kicad_pcb
	(version 20241229)
	(generator "pcbnew")
	(generator_version "9.0")
	(general
		(thickness 1.61)
		(legacy_teardrops no)
	)
	(paper "A3")
	(title_block
		(title "RDIMM DDR5 Tester")
		(date "2026-05-21")
		(rev "2.2.0")
		(company "Antmicro")
		(comment 9 "footprints 110-113 of 796")
	)
	(layers
		(0 "F.Cu" signal)
		(4 "In1.Cu" power)
		(6 "In2.Cu" mixed)
		(8 "In3.Cu" power)
		(10 "In4.Cu" mixed)
		(12 "In5.Cu" power)
		(14 "In6.Cu" mixed)
		(16 "In7.Cu" power)
		(18 "In8.Cu" power)
		(20 "In9.Cu" mixed)
		(22 "In10.Cu" power)
		(2 "B.Cu" signal)
		(9 "F.Adhes" user "F.Adhesive")
		(11 "B.Adhes" user "B.Adhesive")
		(13 "F.Paste" user)
		(15 "B.Paste" user)
		(5 "F.SilkS" user "F.Silkscreen")
		(7 "B.SilkS" user "B.Silkscreen")
		(1 "F.Mask" user)
		(3 "B.Mask" user)
		(17 "Dwgs.User" user "User.Drawings")
		(19 "Cmts.User" user "User.Comments")
		(21 "Eco1.User" user "User.Eco1")
		(23 "Eco2.User" user "User.Eco2")
		(25 "Edge.Cuts" user)
		(27 "Margin" user)
		(31 "F.CrtYd" user "F.Courtyard")
		(29 "B.CrtYd" user "B.Courtyard")
		(35 "F.Fab" user)
		(33 "B.Fab" user)
	)
	(footprint "antmicro-footprints:SOT-23-5"
		(layer "F.Cu")
		(at 254.287998 128.939)
		(property "Reference" "U21"
			(at -2.363499 2.81 90)
			(layer "F.SilkS")
			(effects
				(font
					(size 0.7 0.7)
					(thickness 0.15)
				)
				(justify left bottom)
			)
		)
		(property "Value" "NCP718BSN330T1G"
			(at 0.002 2.799 0)
			(layer "F.Fab")
			(effects
				(font
					(size 0.7 0.7)
					(thickness 0.15)
				)
				(justify left bottom)
			)
		)
		(property "Datasheet" "https://www.mouser.com/datasheet/2/308/NCP718_D-1224359.pdf"
			(at 0 0 0)
			(layer "F.Fab")
			(hide yes)
			(effects
				(font
					(size 1.27 1.27)
					(thickness 0.15)
				)
			)
		)
		(property "MPN" "NCP718BSN330T1G"
			(at 0 0 0)
			(unlocked yes)
			(layer "F.Fab")
			(hide yes)
			(effects
				(font
					(size 1 1)
					(thickness 0.15)
				)
			)
		)
		(property "Manufacturer" "ON Semiconductor"
			(at 0 0 0)
			(unlocked yes)
			(layer "F.Fab")
			(hide yes)
			(effects
				(font
					(size 1 1)
					(thickness 0.15)
				)
			)
		)
		(property "Author" "Antmicro"
			(at 0 0 0)
			(unlocked yes)
			(layer "F.Fab")
			(hide yes)
			(effects
				(font
					(size 1 1)
					(thickness 0.15)
				)
			)
		)
		(property "License" "Apache-2.0"
			(at 0 0 0)
			(unlocked yes)
			(layer "F.Fab")
			(hide yes)
			(effects
				(font
					(size 1 1)
					(thickness 0.15)
				)
			)
		)
		(sheetname "/Supply/")
		(sheetfile "supply.kicad_sch")
		(attr smd)
		(fp_line
			(start -0.85 1.6)
			(end -0.85 1.301)
			(stroke
				(width 0.15)
				(type solid)
			)
			(layer "F.SilkS")
		)
		(fp_line
			(start -0.8 -1.6)
			(end -0.8 -1.3)
			(stroke
				(width 0.15)
				(type solid)
			)
			(layer "F.SilkS")
		)
		(fp_line
			(start -0.8 -1.6)
			(end -0.5 -1.6)
			(stroke
				(width 0.15)
				(type solid)
			)
			(layer "F.SilkS")
		)
		(fp_line
			(start -0.55 1.6)
			(end -0.85 1.6)
			(stroke
				(width 0.15)
				(type solid)
			)
			(layer "F.SilkS")
		)
		(fp_line
			(start 0.8 -1.6)
			(end 0.5 -1.6)
			(stroke
				(width 0.15)
				(type solid)
			)
			(layer "F.SilkS")
		)
		(fp_line
			(start 0.8 -1.3)
			(end 0.8 -1.6)
			(stroke
				(width 0.15)
				(type solid)
			)
			(layer "F.SilkS")
		)
		(fp_line
			(start 0.8 0.55)
			(end 0.8 -0.55)
			(stroke
				(width 0.15)
				(type solid)
			)
			(layer "F.SilkS")
		)
		(fp_line
			(start 0.8 1.3)
			(end 0.8 1.599)
			(stroke
				(width 0.15)
				(type solid)
			)
			(layer "F.SilkS")
		)
		(fp_line
			(start 0.8 1.599)
			(end 0.549 1.599)
			(stroke
				(width 0.15)
				(type solid)
			)
			(layer "F.SilkS")
		)
		(fp_circle
			(center -1.25 -1.5)
			(end -1.2 -1.5)
			(stroke
				(width 0.15)
				(type solid)
			)
			(fill yes)
			(layer "F.SilkS")
		)
		(fp_rect
			(start 1.9 -1.76)
			(end -1.9 1.75)
			(stroke
				(width 0.05)
				(type solid)
			)
			(fill no)
			(layer "F.CrtYd")
		)
		(fp_line
			(start -0.398 -1.526)
			(end -0.874 -1.05)
			(stroke
				(width 0.15)
				(type solid)
			)
			(layer "F.Fab")
		)
		(fp_rect
			(start 0.874 1.523)
			(end -0.873 -1.525)
			(stroke
				(width 0.15)
				(type solid)
			)
			(fill no)
			(layer "F.Fab")
		)
		(fp_text user "Author: Antmicro"
			(at -1.898 5.499 0)
			(layer "F.Fab")
			(effects
				(font
					(size 0.7 0.7)
					(thickness 0.15)
				)
				(justify left bottom)
			)
		)
		(fp_text user "${REFERENCE}"
			(at -1.898 4.299 0)
			(layer "F.Fab")
			(effects
				(font
					(size 0.7 0.7)
					(thickness 0.15)
				)
				(justify left bottom)
			)
		)
		(fp_text user "License: Apache-2.0"
			(at -1.898 6.7 0)
			(layer "F.Fab")
			(effects
				(font
					(size 0.7 0.7)
					(thickness 0.15)
				)
				(justify left bottom)
			)
		)
		(pad "1" smd rect
			(at -1.351 -0.951 270)
			(size 0.55 1)
			(layers "F.Cu" "F.Mask" "F.Paste")
			(net 35 "VDC")
			(pinfunction "VIN")
			(pintype "passive")
		)
		(pad "2" smd rect
			(at -1.351 0 270)
			(size 0.55 1)
			(layers "F.Cu" "F.Mask" "F.Paste")
			(net 1 "GND")
			(pinfunction "GND")
			(pintype "passive")
		)
		(pad "3" smd rect
			(at -1.351 0.949 270)
			(size 0.55 1)
			(layers "F.Cu" "F.Mask" "F.Paste")
			(net 35 "VDC")
			(pinfunction "EN")
			(pintype "passive")
		)
		(pad "4" smd rect
			(at 1.35 0.949 270)
			(size 0.55 1)
			(layers "F.Cu" "F.Mask" "F.Paste")
			(net 434 "unconnected-(U21-NC-Pad4)")
			(pinfunction "NC")
			(pintype "no_connect")
		)
		(pad "5" smd rect
			(at 1.35 -0.951 270)
			(size 0.55 1)
			(layers "F.Cu" "F.Mask" "F.Paste")
			(net 38 "+3V3_AON")
			(pinfunction "VOUT")
			(pintype "passive")
		)
	)
	(footprint "antmicro-footprints:C_0402_1005Metric"
		(layer "F.Cu")
		(at 150.375499 169.033 -90)
		(descr "Capacitor SMD 0402")
		(tags "capacitor SMD 0402")
		(property "Reference" "C130"
			(at -2.233 -1.964501 90)
			(layer "F.SilkS")
			(effects
				(font
					(size 0.7 0.7)
					(thickness 0.15)
				)
				(justify right bottom)
			)
		)
		(property "Value" "C_100n_0402"
			(at -1.022927 2.155213 90)
			(layer "F.Fab")
			(effects
				(font
					(size 0.7 0.7)
					(thickness 0.15)
				)
				(justify right bottom)
			)
		)
		(property "Datasheet" "https://www.murata.com/products/productdetail?partno=GRM155R61H104KE14%23"
			(at 0 0 270)
			(layer "F.Fab")
			(hide yes)
			(effects
				(font
					(size 1.27 1.27)
					(thickness 0.15)
				)
			)
		)
		(property "MPN" "GRM155R61H104KE14D"
			(at 0 0 270)
			(unlocked yes)
			(layer "F.Fab")
			(hide yes)
			(effects
				(font
					(size 1 1)
					(thickness 0.15)
				)
			)
		)
		(property "Manufacturer" "Murata"
			(at 0 0 270)
			(unlocked yes)
			(layer "F.Fab")
			(hide yes)
			(effects
				(font
					(size 1 1)
					(thickness 0.15)
				)
			)
		)
		(property "License" "Apache-2.0"
			(at 0 0 270)
			(unlocked yes)
			(layer "F.Fab")
			(hide yes)
			(effects
				(font
					(size 1 1)
					(thickness 0.15)
				)
			)
		)
		(property "Author" "Antmicro"
			(at 0 0 270)
			(unlocked yes)
			(layer "F.Fab")
			(hide yes)
			(effects
				(font
					(size 1 1)
					(thickness 0.15)
				)
			)
		)
		(property "Val" "100n"
			(at 0 0 270)
			(unlocked yes)
			(layer "F.Fab")
			(hide yes)
			(effects
				(font
					(size 1 1)
					(thickness 0.15)
				)
			)
		)
		(property "Voltage" "50V"
			(at 0 0 270)
			(unlocked yes)
			(layer "F.Fab")
			(hide yes)
			(effects
				(font
					(size 1 1)
					(thickness 0.15)
				)
			)
		)
		(property "Dielectric" "X5R"
			(at 0 0 270)
			(unlocked yes)
			(layer "F.Fab")
			(hide yes)
			(effects
				(font
					(size 1 1)
					(thickness 0.15)
				)
			)
		)
		(sheetname "/Debug FTDI + VNA/")
		(sheetfile "debug-ftdi.kicad_sch")
		(attr smd)
		(fp_rect
			(start -0.925 -0.47)
			(end 0.925 0.47)
			(stroke
				(width 0.05)
				(type default)
			)
			(fill no)
			(layer "F.CrtYd")
		)
		(fp_line
			(start -0.494 0.248)
			(end -0.494 -0.25)
			(stroke
				(width 0.15)
				(type solid)
			)
			(layer "F.Fab")
		)
		(fp_line
			(start 0.504 0.248)
			(end -0.494 0.248)
			(stroke
				(width 0.15)
				(type solid)
			)
			(layer "F.Fab")
		)
		(fp_line
			(start -0.494 -0.25)
			(end 0.504 -0.25)
			(stroke
				(width 0.15)
				(type solid)
			)
			(layer "F.Fab")
		)
		(fp_line
			(start 0.504 -0.25)
			(end 0.504 0.248)
			(stroke
				(width 0.15)
				(type solid)
			)
			(layer "F.Fab")
		)
		(fp_text user "Author: Antmicro"
			(at -0.939 3.399 270)
			(layer "F.Fab")
			(effects
				(font
					(size 0.7 0.7)
					(thickness 0.15)
				)
				(justify left bottom)
			)
		)
		(fp_text user "${REFERENCE}"
			(at -0.939 4.599 270)
			(layer "F.Fab")
			(effects
				(font
					(size 0.7 0.7)
					(thickness 0.15)
				)
				(justify left bottom)
			)
		)
		(fp_text user "License: Apache-2.0"
			(at -0.939 5.799 270)
			(layer "F.Fab")
			(effects
				(font
					(size 0.7 0.7)
					(thickness 0.15)
				)
				(justify left bottom)
			)
		)
		(pad "1" smd roundrect
			(at -0.48 0 270)
			(size 0.59 0.64)
			(layers "F.Cu" "F.Mask" "F.Paste")
			(roundrect_rratio 0.25)
			(net 1 "GND")
			(pintype "passive")
		)
		(pad "2" smd roundrect
			(at 0.48 0 270)
			(size 0.59 0.64)
			(layers "F.Cu" "F.Mask" "F.Paste")
			(roundrect_rratio 0.25)
			(net 6 "/Debug FTDI + VNA/FTDI_3V3")
			(pintype "passive")
		)
	)
	(footprint "antmicro-footprints:USON-10_2.5x1mm_P0.5mm"
		(layer "F.Cu")
		(at 220.857 148.098 180)
		(descr "USON-10 2.5x1mm_ Pitch 0.5mm")
		(tags "USON-10 2.5x1mm Pitch 0.5mm")
		(property "Reference" "U2"
			(at -0.543 -2.552 0)
			(layer "F.SilkS")
			(effects
				(font
					(size 0.7 0.7)
					(thickness 0.15)
				)
				(justify right bottom)
			)
		)
		(property "Value" "TPD4E05U06QDQARQ1"
			(at 0.018 2.499 0)
			(layer "F.Fab")
			(effects
				(font
					(size 0.7 0.7)
					(thickness 0.15)
				)
				(justify right bottom)
			)
		)
		(property "Datasheet" "https://www.ti.com/lit/ds/symlink/tpd4e05u06-q1.pdf?HQS=dis-mous-null-mousermode-dsf-pf-null-wwe&ts=1663591265741&ref_url=https%253A%252F%252Fwww.mouser.com%252F"
			(at 0 0 180)
			(layer "F.Fab")
			(hide yes)
			(effects
				(font
					(size 1.27 1.27)
					(thickness 0.15)
				)
			)
		)
		(property "MPN" "TPD4E05U06QDQARQ1"
			(at 0 0 180)
			(unlocked yes)
			(layer "F.Fab")
			(hide yes)
			(effects
				(font
					(size 1 1)
					(thickness 0.15)
				)
			)
		)
		(property "Manufacturer" "Texas Instruments"
			(at 0 0 180)
			(unlocked yes)
			(layer "F.Fab")
			(hide yes)
			(effects
				(font
					(size 1 1)
					(thickness 0.15)
				)
			)
		)
		(property "Author" "Antmicro"
			(at 0 0 180)
			(unlocked yes)
			(layer "F.Fab")
			(hide yes)
			(effects
				(font
					(size 1 1)
					(thickness 0.15)
				)
			)
		)
		(property "License" "Apache-2.0"
			(at 0 0 180)
			(unlocked yes)
			(layer "F.Fab")
			(hide yes)
			(effects
				(font
					(size 1 1)
					(thickness 0.15)
				)
			)
		)
		(sheetname "/FPGA Config/")
		(sheetfile "fpga-config.kicad_sch")
		(attr smd)
		(fp_line
			(start 0.498 1.398)
			(end -0.5 1.398)
			(stroke
				(width 0.15)
				(type solid)
			)
			(layer "F.SilkS")
		)
		(fp_line
			(start 0.498 -1.401)
			(end -0.5 -1.401)
			(stroke
				(width 0.15)
				(type solid)
			)
			(layer "F.SilkS")
		)
		(fp_circle
			(center -0.68 -1.27)
			(end -0.63 -1.27)
			(stroke
				(width 0.15)
				(type solid)
			)
			(fill yes)
			(layer "F.SilkS")
		)
		(fp_rect
			(start -0.8 -1.5)
			(end 0.8 1.499)
			(stroke
				(width 0.05)
				(type solid)
			)
			(fill no)
			(layer "F.CrtYd")
		)
		(fp_line
			(start 0.498 -1.25)
			(end 0.498 1.249)
			(stroke
				(width 0.15)
				(type solid)
			)
			(layer "F.Fab")
		)
		(fp_line
			(start 0.498 -1.25)
			(end -0.25 -1.25)
			(stroke
				(width 0.15)
				(type solid)
			)
			(layer "F.Fab")
		)
		(fp_line
			(start -0.25 -1.25)
			(end -0.5 -1)
			(stroke
				(width 0.15)
				(type solid)
			)
			(layer "F.Fab")
		)
		(fp_line
			(start -0.5 1.249)
			(end 0.498 1.249)
			(stroke
				(width 0.15)
				(type solid)
			)
			(layer "F.Fab")
		)
		(fp_line
			(start -0.5 -1)
			(end -0.5 1.249)
			(stroke
				(width 0.15)
				(type solid)
			)
			(layer "F.Fab")
		)
		(fp_text user "${REFERENCE}"
			(at -0.802 4.498 180)
			(layer "F.Fab")
			(effects
				(font
					(size 0.7 0.7)
					(thickness 0.15)
				)
				(justify left bottom)
			)
		)
		(fp_text user "Author: Antmicro"
			(at -0.802 5.7 180)
			(layer "F.Fab")
			(effects
				(font
					(size 0.7 0.7)
					(thickness 0.15)
				)
				(justify left bottom)
			)
		)
		(fp_text user "License: Apache-2.0"
			(at -0.802 6.9 180)
			(layer "F.Fab")
			(effects
				(font
					(size 0.7 0.7)
					(thickness 0.15)
				)
				(justify left bottom)
			)
		)
		(pad "1" smd roundrect
			(at -0.387 -1 90)
			(size 0.25 0.55)
			(layers "F.Cu" "F.Mask" "F.Paste")
			(roundrect_rratio 0.25)
			(net 238 "/Debug FTDI + VNA/JTAG.TMS")
			(pintype "passive")
		)
		(pad "2" smd roundrect
			(at -0.387 -0.5 90)
			(size 0.25 0.55)
			(layers "F.Cu" "F.Mask" "F.Paste")
			(roundrect_rratio 0.25)
			(net 239 "/Debug FTDI + VNA/JTAG.TCK")
			(pintype "passive")
		)
		(pad "3" smd roundrect
			(at -0.387 0 90)
			(size 0.4 0.55)
			(layers "F.Cu" "F.Mask" "F.Paste")
			(roundrect_rratio 0.25)
			(net 1 "GND")
			(pintype "power_in")
		)
		(pad "4" smd roundrect
			(at -0.387 0.498 90)
			(size 0.25 0.55)
			(layers "F.Cu" "F.Mask" "F.Paste")
			(roundrect_rratio 0.25)
			(net 242 "/Debug FTDI + VNA/JTAG.TDO")
			(pintype "passive")
		)
		(pad "5" smd roundrect
			(at -0.387 0.998 90)
			(size 0.25 0.55)
			(layers "F.Cu" "F.Mask" "F.Paste")
			(roundrect_rratio 0.25)
			(net 244 "/Debug FTDI + VNA/JTAG.TDI")
			(pintype "passive")
		)
		(pad "6" smd roundrect
			(at 0.385 0.998 90)
			(size 0.25 0.55)
			(layers "F.Cu" "F.Mask" "F.Paste")
			(roundrect_rratio 0.25)
			(net 244 "/Debug FTDI + VNA/JTAG.TDI")
			(pintype "passive")
		)
		(pad "7" smd roundrect
			(at 0.385 0.498 90)
			(size 0.25 0.55)
			(layers "F.Cu" "F.Mask" "F.Paste")
			(roundrect_rratio 0.25)
			(net 242 "/Debug FTDI + VNA/JTAG.TDO")
			(pintype "passive")
		)
		(pad "8" smd roundrect
			(at 0.385 0 90)
			(size 0.4 0.55)
			(layers "F.Cu" "F.Mask" "F.Paste")
			(roundrect_rratio 0.25)
			(net 1 "GND")
			(pintype "passive")
		)
		(pad "9" smd roundrect
			(at 0.385 -0.5 90)
			(size 0.25 0.55)
			(layers "F.Cu" "F.Mask" "F.Paste")
			(roundrect_rratio 0.25)
			(net 239 "/Debug FTDI + VNA/JTAG.TCK")
			(pintype "passive")
		)
		(pad "10" smd roundrect
			(at 0.385 -1 90)
			(size 0.25 0.55)
			(layers "F.Cu" "F.Mask" "F.Paste")
			(roundrect_rratio 0.25)
			(net 238 "/Debug FTDI + VNA/JTAG.TMS")
			(pintype "passive")
		)
	)
	(footprint "antmicro-footprints:L_0402_1005Metric"
		(layer "F.Cu")
		(at 121.025 151.61 180)
		(descr "Inductor SMD 0402")
		(tags "Inductor SMD 0402")
		(property "Reference" "L10"
			(at -5.745 -0.415 0)
			(layer "F.SilkS")
			(effects
				(font
					(size 0.7 0.7)
					(thickness 0.15)
				)
				(justify right bottom)
			)
		)
		(property "Value" "L_20n_0.35A_0402"
			(at 0 1.4 0)
			(layer "F.Fab")
			(effects
				(font
					(size 0.7 0.7)
					(thickness 0.15)
				)
				(justify right bottom)
			)
		)
		(property "Datasheet" "https://product.tdk.com/system/files/dam/doc/product/inductor/inductor/smd/catalog/inductor_automotive_high-frequency_mlg1005s_en.pdf?ref_disty=mouser"
			(at 0 0 180)
			(layer "F.Fab")
			(hide yes)
			(effects
				(font
					(size 1.27 1.27)
					(thickness 0.15)
				)
			)
		)
		(property "Val" "20n/0.35A"
			(at 0 0 180)
			(unlocked yes)
			(layer "F.Fab")
			(hide yes)
			(effects
				(font
					(size 1 1)
					(thickness 0.15)
				)
			)
		)
		(property "Manufacturer" "TDK"
			(at 0 0 180)
			(unlocked yes)
			(layer "F.Fab")
			(hide yes)
			(effects
				(font
					(size 1 1)
					(thickness 0.15)
				)
			)
		)
		(property "MPN" "MLG1005S20NJTD25"
			(at 0 0 180)
			(unlocked yes)
			(layer "F.Fab")
			(hide yes)
			(effects
				(font
					(size 1 1)
					(thickness 0.15)
				)
			)
		)
		(property "ISat" ""
			(at 0 0 180)
			(unlocked yes)
			(layer "F.Fab")
			(hide yes)
			(effects
				(font
					(size 1 1)
					(thickness 0.15)
				)
			)
		)
		(property "IMax" "0.35 A"
			(at 0 0 180)
			(unlocked yes)
			(layer "F.Fab")
			(hide yes)
			(effects
				(font
					(size 1 1)
					(thickness 0.15)
				)
			)
		)
		(property "Size" "1.0x0.5"
			(at 0 0 180)
			(unlocked yes)
			(layer "F.Fab")
			(hide yes)
			(effects
				(font
					(size 1 1)
					(thickness 0.15)
				)
			)
		)
		(property "Author" "Antmicro"
			(at 0 0 180)
			(unlocked yes)
			(layer "F.Fab")
			(hide yes)
			(effects
				(font
					(size 1 1)
					(thickness 0.15)
				)
			)
		)
		(property "License" "Apache-2.0"
			(at 0 0 180)
			(unlocked yes)
			(layer "F.Fab")
			(hide yes)
			(effects
				(font
					(size 1 1)
					(thickness 0.15)
				)
			)
		)
		(sheetname "/HDMI + SD Card/")
		(sheetfile "hdmi-sd-card.kicad_sch")
		(attr smd)
		(fp_rect
			(start -0.925 -0.47)
			(end 0.925 0.47)
			(stroke
				(width 0.05)
				(type default)
			)
			(fill no)
			(layer "F.CrtYd")
		)
		(fp_rect
			(start -0.499 -0.249)
			(end 0.499 0.249)
			(stroke
				(width 0.15)
				(type solid)
			)
			(fill no)
			(layer "F.Fab")
		)
		(fp_text user "${REFERENCE}"
			(at -0.932 3.168 180)
			(layer "F.Fab")
			(effects
				(font
					(size 0.7 0.7)
					(thickness 0.15)
				)
				(justify left bottom)
			)
		)
		(fp_text user "Author: Antmicro"
			(at -0.932 4.17 180)
			(layer "F.Fab")
			(effects
				(font
					(size 0.7 0.7)
					(thickness 0.15)
				)
				(justify left bottom)
			)
		)
		(fp_text user "License: Apache-2.0"
			(at -0.932 5.17 180)
			(layer "F.Fab")
			(effects
				(font
					(size 0.7 0.7)
					(thickness 0.15)
				)
				(justify left bottom)
			)
		)
		(pad "1" smd roundrect
			(at -0.48 0 180)
			(size 0.59 0.64)
			(layers "F.Cu" "F.Mask" "F.Paste")
			(roundrect_rratio 0.25)
			(net 380 "/FPGA MGT Interface/HDMI_IN.D0_P")
			(pintype "passive")
		)
		(pad "2" smd roundrect
			(at 0.48 0 180)
			(size 0.59 0.64)
			(layers "F.Cu" "F.Mask" "F.Paste")
			(roundrect_rratio 0.25)
			(net 680 "Net-(L10-Pad2)")
			(pintype "passive")
		)
	)
)
